(kicad_pcb
	(version 20260206)
	(generator "pcbnew")
	(generator_version "10.0")
	(general
		(thickness 1.6)
		(legacy_teardrops no)
	)
	(paper "A4")
	(title_block
		(title "01162023_DA0F0TEBIF0_F0T_Expander_BD_F_brd_V02_OCP.brd")
		(comment 1 "Grand Teton / footprints 5556-5562 of 9728")
	)
	(layers
		(0 "F.Cu" signal "TOP")
		(4 "In1.Cu" signal "GND")
		(6 "In2.Cu" signal "VCC")
		(8 "In3.Cu" signal "VCC1")
		(10 "In4.Cu" signal "GND1")
		(12 "In5.Cu" signal "IN1")
		(14 "In6.Cu" signal "GND2")
		(16 "In7.Cu" signal "IN2")
		(18 "In8.Cu" signal "GND3")
		(20 "In9.Cu" signal "IN3")
		(22 "In10.Cu" signal "GND4")
		(24 "In11.Cu" signal "IN4")
		(26 "In12.Cu" signal "GND5")
		(28 "In13.Cu" signal "IN5")
		(30 "In14.Cu" signal "GND6")
		(32 "In15.Cu" signal "IN6")
		(34 "In16.Cu" signal "GND7")
		(2 "B.Cu" signal "BOTTOM")
		(9 "F.Adhes" user "F.Adhesive")
		(11 "B.Adhes" user "B.Adhesive")
		(13 "F.Paste" user "Package Geometry/Pastemask Top")
		(15 "B.Paste" user "Package Geometry/Pastemask Bottom")
		(5 "F.SilkS" user "Ref Des/Silkscreen Top")
		(7 "B.SilkS" user "Ref Des/Silkscreen Bottom")
		(1 "F.Mask" user "Board Geometry/Soldermask Top")
		(3 "B.Mask" user "Board Geometry/Soldermask Bottom")
		(17 "Dwgs.User" user "User.Drawings")
		(19 "Cmts.User" user "User.Comments")
		(21 "Eco1.User" user "User.Eco1")
		(23 "Eco2.User" user "User.Eco2")
		(25 "Edge.Cuts" user "Board Geometry/Outline")
		(27 "Margin" user)
		(31 "F.CrtYd" user "Package Geometry/Place Bound Top")
		(29 "B.CrtYd" user "Package Geometry/Place Bound Bottom")
		(35 "F.Fab" user "Ref Des/Assembly Top")
		(33 "B.Fab" user "Ref Des/Assembly Bottom")
	)
	(footprint ""
		(layer "F.Cu")
		(at 171.972224 -32.848042 90)
		(property "Reference" "PC930"
			(at 0 0 90)
			(layer "F.SilkS")
			(hide yes)
			(effects
				(font
					(size 1.27 1.27)
				)
			)
		)
		(property "Value" ""
			(at 0 0 90)
			(layer "F.Fab")
			(effects
				(font
					(size 1.27 1.27)
				)
			)
		)
		(duplicate_pad_numbers_are_jumpers no)
		(fp_line
			(start 0.7874 -0.4064)
			(end 0.7874 0.4064)
			(stroke
				(width 0.1524)
				(type default)
			)
			(layer "F.SilkS")
		)
		(fp_line
			(start -0.7874 -0.4064)
			(end 0.7874 -0.4064)
			(stroke
				(width 0.1524)
				(type default)
			)
			(layer "F.SilkS")
		)
		(fp_line
			(start 0.7874 0.4064)
			(end -0.7874 0.4064)
			(stroke
				(width 0.1524)
				(type default)
			)
			(layer "F.SilkS")
		)
		(fp_line
			(start -0.7874 0.4064)
			(end -0.7874 -0.4064)
			(stroke
				(width 0.1524)
				(type default)
			)
			(layer "F.SilkS")
		)
		(fp_line
			(start -0.12065 -0.305054)
			(end -0.12065 -0.2794)
			(stroke
				(width 0.1)
				(type default)
			)
			(layer "F.Fab")
		)
		(fp_line
			(start -0.67945 -0.305054)
			(end -0.12065 -0.305054)
			(stroke
				(width 0.1)
				(type default)
			)
			(layer "F.Fab")
		)
		(fp_line
			(start 0.67945 -0.3048)
			(end 0.67945 0.3048)
			(stroke
				(width 0.1)
				(type default)
			)
			(layer "F.Fab")
		)
		(fp_line
			(start 0.12065 -0.3048)
			(end 0.67945 -0.3048)
			(stroke
				(width 0.1)
				(type default)
			)
			(layer "F.Fab")
		)
		(fp_line
			(start 0.12065 -0.2794)
			(end 0.12065 -0.3048)
			(stroke
				(width 0.1)
				(type default)
			)
			(layer "F.Fab")
		)
		(fp_line
			(start -0.12065 -0.2794)
			(end 0.12065 -0.2794)
			(stroke
				(width 0.1)
				(type default)
			)
			(layer "F.Fab")
		)
		(fp_line
			(start 0.120396 0.2794)
			(end -0.12065 0.2794)
			(stroke
				(width 0.1)
				(type default)
			)
			(layer "F.Fab")
		)
		(fp_line
			(start -0.12065 0.2794)
			(end -0.12065 0.3048)
			(stroke
				(width 0.1)
				(type default)
			)
			(layer "F.Fab")
		)
		(fp_line
			(start 0.67945 0.3048)
			(end 0.120396 0.3048)
			(stroke
				(width 0.1)
				(type default)
			)
			(layer "F.Fab")
		)
		(fp_line
			(start 0.120396 0.3048)
			(end 0.120396 0.2794)
			(stroke
				(width 0.1)
				(type default)
			)
			(layer "F.Fab")
		)
		(fp_line
			(start -0.12065 0.3048)
			(end -0.67945 0.3048)
			(stroke
				(width 0.1)
				(type default)
			)
			(layer "F.Fab")
		)
		(fp_line
			(start -0.67945 0.3048)
			(end -0.67945 -0.305054)
			(stroke
				(width 0.1)
				(type default)
			)
			(layer "F.Fab")
		)
		(pad "1" smd circle
			(at -0.40005 0 90)
			(size 0 0)
			(layers "F.Cu" "F.Mask" "F.Paste")
			(net "P3V3_SSD6_CO_GATE")
		)
		(pad "2" smd circle
			(at 0.40005 0 90)
			(size 0 0)
			(layers "F.Cu" "F.Mask" "F.Paste")
			(net "GND")
		)
	)
	(footprint ""
		(layer "F.Cu")
		(at 399.5928 -85.3948)
		(property "Reference" "C3994"
			(at 0 0 0)
			(layer "F.SilkS")
			(hide yes)
			(effects
				(font
					(size 1.27 1.27)
				)
			)
		)
		(property "Value" ""
			(at 0 0 0)
			(layer "F.Fab")
			(effects
				(font
					(size 1.27 1.27)
				)
			)
		)
		(duplicate_pad_numbers_are_jumpers no)
		(fp_line
			(start -0.7874 -0.4064)
			(end 0.7874 -0.4064)
			(stroke
				(width 0.1524)
				(type default)
			)
			(layer "F.SilkS")
		)
		(fp_line
			(start -0.7874 0.4064)
			(end -0.7874 -0.4064)
			(stroke
				(width 0.1524)
				(type default)
			)
			(layer "F.SilkS")
		)
		(fp_line
			(start 0.7874 -0.4064)
			(end 0.7874 0.4064)
			(stroke
				(width 0.1524)
				(type default)
			)
			(layer "F.SilkS")
		)
		(fp_line
			(start 0.7874 0.4064)
			(end -0.7874 0.4064)
			(stroke
				(width 0.1524)
				(type default)
			)
			(layer "F.SilkS")
		)
		(fp_line
			(start -0.67945 -0.305054)
			(end -0.12065 -0.305054)
			(stroke
				(width 0.1)
				(type default)
			)
			(layer "F.Fab")
		)
		(fp_line
			(start -0.67945 0.3048)
			(end -0.67945 -0.305054)
			(stroke
				(width 0.1)
				(type default)
			)
			(layer "F.Fab")
		)
		(fp_line
			(start -0.12065 -0.305054)
			(end -0.12065 -0.2794)
			(stroke
				(width 0.1)
				(type default)
			)
			(layer "F.Fab")
		)
		(fp_line
			(start -0.12065 -0.2794)
			(end 0.12065 -0.2794)
			(stroke
				(width 0.1)
				(type default)
			)
			(layer "F.Fab")
		)
		(fp_line
			(start -0.12065 0.2794)
			(end -0.12065 0.3048)
			(stroke
				(width 0.1)
				(type default)
			)
			(layer "F.Fab")
		)
		(fp_line
			(start -0.12065 0.3048)
			(end -0.67945 0.3048)
			(stroke
				(width 0.1)
				(type default)
			)
			(layer "F.Fab")
		)
		(fp_line
			(start 0.120396 0.2794)
			(end -0.12065 0.2794)
			(stroke
				(width 0.1)
				(type default)
			)
			(layer "F.Fab")
		)
		(fp_line
			(start 0.120396 0.3048)
			(end 0.120396 0.2794)
			(stroke
				(width 0.1)
				(type default)
			)
			(layer "F.Fab")
		)
		(fp_line
			(start 0.12065 -0.3048)
			(end 0.67945 -0.3048)
			(stroke
				(width 0.1)
				(type default)
			)
			(layer "F.Fab")
		)
		(fp_line
			(start 0.12065 -0.2794)
			(end 0.12065 -0.3048)
			(stroke
				(width 0.1)
				(type default)
			)
			(layer "F.Fab")
		)
		(fp_line
			(start 0.67945 -0.3048)
			(end 0.67945 0.3048)
			(stroke
				(width 0.1)
				(type default)
			)
			(layer "F.Fab")
		)
		(fp_line
			(start 0.67945 0.3048)
			(end 0.120396 0.3048)
			(stroke
				(width 0.1)
				(type default)
			)
			(layer "F.Fab")
		)
		(pad "1" smd circle
			(at -0.40005 0)
			(size 0 0)
			(layers "F.Cu" "F.Mask" "F.Paste")
			(net "GND")
		)
		(pad "2" smd circle
			(at 0.40005 0)
			(size 0 0)
			(layers "F.Cu" "F.Mask" "F.Paste")
			(net "P3V3_AUX")
		)
	)
	(footprint ""
		(layer "F.Cu")
		(at 219.202 -207.772)
		(property "Reference" "R1508"
			(at 0 0 0)
			(layer "F.SilkS")
			(hide yes)
			(effects
				(font
					(size 1.27 1.27)
				)
			)
		)
		(property "Value" ""
			(at 0 0 0)
			(layer "F.Fab")
			(effects
				(font
					(size 1.27 1.27)
				)
			)
		)
		(duplicate_pad_numbers_are_jumpers no)
		(fp_line
			(start -0.7874 -0.4064)
			(end 0.7874 -0.4064)
			(stroke
				(width 0.1524)
				(type default)
			)
			(layer "F.SilkS")
		)
		(fp_line
			(start -0.7874 0.4064)
			(end -0.7874 -0.4064)
			(stroke
				(width 0.1524)
				(type default)
			)
			(layer "F.SilkS")
		)
		(fp_line
			(start 0.7874 -0.4064)
			(end 0.7874 0.4064)
			(stroke
				(width 0.1524)
				(type default)
			)
			(layer "F.SilkS")
		)
		(fp_line
			(start 0.7874 0.4064)
			(end -0.7874 0.4064)
			(stroke
				(width 0.1524)
				(type default)
			)
			(layer "F.SilkS")
		)
		(fp_line
			(start -0.67945 -0.305054)
			(end -0.12065 -0.305054)
			(stroke
				(width 0.1)
				(type default)
			)
			(layer "F.Fab")
		)
		(fp_line
			(start -0.67945 0.3048)
			(end -0.67945 -0.305054)
			(stroke
				(width 0.1)
				(type default)
			)
			(layer "F.Fab")
		)
		(fp_line
			(start -0.12065 -0.305054)
			(end -0.12065 -0.2794)
			(stroke
				(width 0.1)
				(type default)
			)
			(layer "F.Fab")
		)
		(fp_line
			(start -0.12065 -0.2794)
			(end 0.12065 -0.2794)
			(stroke
				(width 0.1)
				(type default)
			)
			(layer "F.Fab")
		)
		(fp_line
			(start -0.12065 0.2794)
			(end -0.12065 0.3048)
			(stroke
				(width 0.1)
				(type default)
			)
			(layer "F.Fab")
		)
		(fp_line
			(start -0.12065 0.3048)
			(end -0.67945 0.3048)
			(stroke
				(width 0.1)
				(type default)
			)
			(layer "F.Fab")
		)
		(fp_line
			(start 0.120396 0.2794)
			(end -0.12065 0.2794)
			(stroke
				(width 0.1)
				(type default)
			)
			(layer "F.Fab")
		)
		(fp_line
			(start 0.120396 0.3048)
			(end 0.120396 0.2794)
			(stroke
				(width 0.1)
				(type default)
			)
			(layer "F.Fab")
		)
		(fp_line
			(start 0.12065 -0.3048)
			(end 0.67945 -0.3048)
			(stroke
				(width 0.1)
				(type default)
			)
			(layer "F.Fab")
		)
		(fp_line
			(start 0.12065 -0.2794)
			(end 0.12065 -0.3048)
			(stroke
				(width 0.1)
				(type default)
			)
			(layer "F.Fab")
		)
		(fp_line
			(start 0.67945 -0.3048)
			(end 0.67945 0.3048)
			(stroke
				(width 0.1)
				(type default)
			)
			(layer "F.Fab")
		)
		(fp_line
			(start 0.67945 0.3048)
			(end 0.120396 0.3048)
			(stroke
				(width 0.1)
				(type default)
			)
			(layer "F.Fab")
		)
		(pad "1" smd circle
			(at -0.40005 0)
			(size 0 0)
			(layers "F.Cu" "F.Mask" "F.Paste")
			(net "SMB_NIC4_LS_R_SDA")
		)
		(pad "2" smd circle
			(at 0.40005 0)
			(size 0 0)
			(layers "F.Cu" "F.Mask" "F.Paste")
			(net "P3V3_NIC4")
		)
	)
	(footprint ""
		(layer "F.Cu")
		(at 258.44373 -42.84091)
		(property "Reference" "R594"
			(at 0 0 0)
			(layer "F.SilkS")
			(hide yes)
			(effects
				(font
					(size 1.27 1.27)
				)
			)
		)
		(property "Value" ""
			(at 0 0 0)
			(layer "F.Fab")
			(effects
				(font
					(size 1.27 1.27)
				)
			)
		)
		(duplicate_pad_numbers_are_jumpers no)
		(fp_line
			(start -0.7874 -0.4064)
			(end 0.7874 -0.4064)
			(stroke
				(width 0.1524)
				(type default)
			)
			(layer "F.SilkS")
		)
		(fp_line
			(start -0.7874 0.4064)
			(end -0.7874 -0.4064)
			(stroke
				(width 0.1524)
				(type default)
			)
			(layer "F.SilkS")
		)
		(fp_line
			(start 0.7874 -0.4064)
			(end 0.7874 0.4064)
			(stroke
				(width 0.1524)
				(type default)
			)
			(layer "F.SilkS")
		)
		(fp_line
			(start 0.7874 0.4064)
			(end -0.7874 0.4064)
			(stroke
				(width 0.1524)
				(type default)
			)
			(layer "F.SilkS")
		)
		(fp_line
			(start -0.67945 -0.305054)
			(end -0.12065 -0.305054)
			(stroke
				(width 0.1)
				(type default)
			)
			(layer "F.Fab")
		)
		(fp_line
			(start -0.67945 0.3048)
			(end -0.67945 -0.305054)
			(stroke
				(width 0.1)
				(type default)
			)
			(layer "F.Fab")
		)
		(fp_line
			(start -0.12065 -0.305054)
			(end -0.12065 -0.2794)
			(stroke
				(width 0.1)
				(type default)
			)
			(layer "F.Fab")
		)
		(fp_line
			(start -0.12065 -0.2794)
			(end 0.12065 -0.2794)
			(stroke
				(width 0.1)
				(type default)
			)
			(layer "F.Fab")
		)
		(fp_line
			(start -0.12065 0.2794)
			(end -0.12065 0.3048)
			(stroke
				(width 0.1)
				(type default)
			)
			(layer "F.Fab")
		)
		(fp_line
			(start -0.12065 0.3048)
			(end -0.67945 0.3048)
			(stroke
				(width 0.1)
				(type default)
			)
			(layer "F.Fab")
		)
		(fp_line
			(start 0.120396 0.2794)
			(end -0.12065 0.2794)
			(stroke
				(width 0.1)
				(type default)
			)
			(layer "F.Fab")
		)
		(fp_line
			(start 0.120396 0.3048)
			(end 0.120396 0.2794)
			(stroke
				(width 0.1)
				(type default)
			)
			(layer "F.Fab")
		)
		(fp_line
			(start 0.12065 -0.3048)
			(end 0.67945 -0.3048)
			(stroke
				(width 0.1)
				(type default)
			)
			(layer "F.Fab")
		)
		(fp_line
			(start 0.12065 -0.2794)
			(end 0.12065 -0.3048)
			(stroke
				(width 0.1)
				(type default)
			)
			(layer "F.Fab")
		)
		(fp_line
			(start 0.67945 -0.3048)
			(end 0.67945 0.3048)
			(stroke
				(width 0.1)
				(type default)
			)
			(layer "F.Fab")
		)
		(fp_line
			(start 0.67945 0.3048)
			(end 0.120396 0.3048)
			(stroke
				(width 0.1)
				(type default)
			)
			(layer "F.Fab")
		)
		(pad "1" smd circle
			(at -0.40005 0)
			(size 0 0)
			(layers "F.Cu" "F.Mask" "F.Paste")
			(net "SSD8_ADC_A1")
		)
		(pad "2" smd circle
			(at 0.40005 0)
			(size 0 0)
			(layers "F.Cu" "F.Mask" "F.Paste")
			(net "P3V3_AUX")
		)
	)
	(footprint ""
		(layer "F.Cu")
		(at 208.149698 -304.036476 90)
		(property "Reference" "R1320"
			(at 0 0 90)
			(layer "F.SilkS")
			(hide yes)
			(effects
				(font
					(size 1.27 1.27)
				)
			)
		)
		(property "Value" ""
			(at 0 0 90)
			(layer "F.Fab")
			(effects
				(font
					(size 1.27 1.27)
				)
			)
		)
		(duplicate_pad_numbers_are_jumpers no)
		(fp_line
			(start 0.7874 -0.4064)
			(end 0.7874 0.4064)
			(stroke
				(width 0.1524)
				(type default)
			)
			(layer "F.SilkS")
		)
		(fp_line
			(start -0.7874 -0.4064)
			(end 0.7874 -0.4064)
			(stroke
				(width 0.1524)
				(type default)
			)
			(layer "F.SilkS")
		)
		(fp_line
			(start 0.7874 0.4064)
			(end -0.7874 0.4064)
			(stroke
				(width 0.1524)
				(type default)
			)
			(layer "F.SilkS")
		)
		(fp_line
			(start -0.7874 0.4064)
			(end -0.7874 -0.4064)
			(stroke
				(width 0.1524)
				(type default)
			)
			(layer "F.SilkS")
		)
		(fp_line
			(start -0.12065 -0.305054)
			(end -0.12065 -0.2794)
			(stroke
				(width 0.1)
				(type default)
			)
			(layer "F.Fab")
		)
		(fp_line
			(start -0.67945 -0.305054)
			(end -0.12065 -0.305054)
			(stroke
				(width 0.1)
				(type default)
			)
			(layer "F.Fab")
		)
		(fp_line
			(start 0.67945 -0.3048)
			(end 0.67945 0.3048)
			(stroke
				(width 0.1)
				(type default)
			)
			(layer "F.Fab")
		)
		(fp_line
			(start 0.12065 -0.3048)
			(end 0.67945 -0.3048)
			(stroke
				(width 0.1)
				(type default)
			)
			(layer "F.Fab")
		)
		(fp_line
			(start 0.12065 -0.2794)
			(end 0.12065 -0.3048)
			(stroke
				(width 0.1)
				(type default)
			)
			(layer "F.Fab")
		)
		(fp_line
			(start -0.12065 -0.2794)
			(end 0.12065 -0.2794)
			(stroke
				(width 0.1)
				(type default)
			)
			(layer "F.Fab")
		)
		(fp_line
			(start 0.120396 0.2794)
			(end -0.12065 0.2794)
			(stroke
				(width 0.1)
				(type default)
			)
			(layer "F.Fab")
		)
		(fp_line
			(start -0.12065 0.2794)
			(end -0.12065 0.3048)
			(stroke
				(width 0.1)
				(type default)
			)
			(layer "F.Fab")
		)
		(fp_line
			(start 0.67945 0.3048)
			(end 0.120396 0.3048)
			(stroke
				(width 0.1)
				(type default)
			)
			(layer "F.Fab")
		)
		(fp_line
			(start 0.120396 0.3048)
			(end 0.120396 0.2794)
			(stroke
				(width 0.1)
				(type default)
			)
			(layer "F.Fab")
		)
		(fp_line
			(start -0.12065 0.3048)
			(end -0.67945 0.3048)
			(stroke
				(width 0.1)
				(type default)
			)
			(layer "F.Fab")
		)
		(fp_line
			(start -0.67945 0.3048)
			(end -0.67945 -0.305054)
			(stroke
				(width 0.1)
				(type default)
			)
			(layer "F.Fab")
		)
		(pad "1" smd circle
			(at -0.40005 0 90)
			(size 0 0)
			(layers "F.Cu" "F.Mask" "F.Paste")
			(net "GND")
		)
		(pad "2" smd circle
			(at 0.40005 0 90)
			(size 0 0)
			(layers "F.Cu" "F.Mask" "F.Paste")
			(net "PEX1_SPARE6")
		)
	)
	(footprint ""
		(layer "F.Cu")
		(at 210.439 -201.803 180)
		(property "Reference" "R1519"
			(at 0 0 180)
			(layer "F.SilkS")
			(hide yes)
			(effects
				(font
					(size 1.27 1.27)
				)
			)
		)
		(property "Value" ""
			(at 0 0 180)
			(layer "F.Fab")
			(effects
				(font
					(size 1.27 1.27)
				)
			)
		)
		(duplicate_pad_numbers_are_jumpers no)
		(fp_line
			(start 0.7874 0.4064)
			(end -0.7874 0.4064)
			(stroke
				(width 0.1524)
				(type default)
			)
			(layer "F.SilkS")
		)
		(fp_line
			(start 0.7874 -0.4064)
			(end 0.7874 0.4064)
			(stroke
				(width 0.1524)
				(type default)
			)
			(layer "F.SilkS")
		)
		(fp_line
			(start -0.7874 0.4064)
			(end -0.7874 -0.4064)
			(stroke
				(width 0.1524)
				(type default)
			)
			(layer "F.SilkS")
		)
		(fp_line
			(start -0.7874 -0.4064)
			(end 0.7874 -0.4064)
			(stroke
				(width 0.1524)
				(type default)
			)
			(layer "F.SilkS")
		)
		(fp_line
			(start 0.67945 0.3048)
			(end 0.120396 0.3048)
			(stroke
				(width 0.1)
				(type default)
			)
			(layer "F.Fab")
		)
		(fp_line
			(start 0.67945 -0.3048)
			(end 0.67945 0.3048)
			(stroke
				(width 0.1)
				(type default)
			)
			(layer "F.Fab")
		)
		(fp_line
			(start 0.12065 -0.2794)
			(end 0.12065 -0.3048)
			(stroke
				(width 0.1)
				(type default)
			)
			(layer "F.Fab")
		)
		(fp_line
			(start 0.12065 -0.3048)
			(end 0.67945 -0.3048)
			(stroke
				(width 0.1)
				(type default)
			)
			(layer "F.Fab")
		)
		(fp_line
			(start 0.120396 0.3048)
			(end 0.120396 0.2794)
			(stroke
				(width 0.1)
				(type default)
			)
			(layer "F.Fab")
		)
		(fp_line
			(start 0.120396 0.2794)
			(end -0.12065 0.2794)
			(stroke
				(width 0.1)
				(type default)
			)
			(layer "F.Fab")
		)
		(fp_line
			(start -0.12065 0.3048)
			(end -0.67945 0.3048)
			(stroke
				(width 0.1)
				(type default)
			)
			(layer "F.Fab")
		)
		(fp_line
			(start -0.12065 0.2794)
			(end -0.12065 0.3048)
			(stroke
				(width 0.1)
				(type default)
			)
			(layer "F.Fab")
		)
		(fp_line
			(start -0.12065 -0.2794)
			(end 0.12065 -0.2794)
			(stroke
				(width 0.1)
				(type default)
			)
			(layer "F.Fab")
		)
		(fp_line
			(start -0.12065 -0.305054)
			(end -0.12065 -0.2794)
			(stroke
				(width 0.1)
				(type default)
			)
			(layer "F.Fab")
		)
		(fp_line
			(start -0.67945 0.3048)
			(end -0.67945 -0.305054)
			(stroke
				(width 0.1)
				(type default)
			)
			(layer "F.Fab")
		)
		(fp_line
			(start -0.67945 -0.305054)
			(end -0.12065 -0.305054)
			(stroke
				(width 0.1)
				(type default)
			)
			(layer "F.Fab")
		)
		(pad "1" smd circle
			(at -0.40005 0 180)
			(size 0 0)
			(layers "F.Cu" "F.Mask" "F.Paste")
			(net "SMB_NIC5_R_SCL")
		)
		(pad "2" smd circle
			(at 0.40005 0 180)
			(size 0 0)
			(layers "F.Cu" "F.Mask" "F.Paste")
			(net "P1V2_AUX")
		)
	)
	(footprint ""
		(layer "F.Cu")
		(at 483.329488 -553.346874 180)
		(property "Reference" "SCREW_SSD12_1"
			(at -5.6007 -1.402334 0)
			(unlocked yes)
			(layer "B.SilkS")
			(effects
				(font
					(size 0.7874 0.5842)
					(thickness 0.1524)
				)
				(justify mirror)
			)
		)
		(property "Value" ""
			(at 0 0 180)
			(layer "F.Fab")
			(effects
				(font
					(size 1.27 1.27)
				)
			)
		)
		(duplicate_pad_numbers_are_jumpers no)
		(pad "1" thru_hole circle
			(at 0 0 180)
			(size 0.4572 0.4572)
			(drill 0.2032)
			(layers "*.Cu" "*.Mask")
			(remove_unused_layers no)
			(net "Net_9150")
			(clearance 0.127)
			(thermal_gap 0.127)
			(padstack
				(mode front_inner_back)
				(layer "Inner"
					(shape circle)
					(size 0.4572 0.4572)
					(clearance 0.127)
				)
				(layer "B.Cu"
					(shape circle)
					(size 0.508 0.508)
					(clearance 0.1016)
				)
			)
		)
	)
)
